# SCM (Grand Teton) — schematic netlist excerpt (pin names and nets, part order shuffled) for the footprints in the layout excerpt that follows; sources: Cadence DE-HDL packaged netlist, KiCad conversion of 12092022_DA0F0TMDCD0_F0T_Management_Board_D_brd_V3_OCP.brd

R163  Q_RES  4.7K 1% CHIP  pkg 0402LF  page 11 : A = P3V3_AUX ; B = FM_CPU_MSMI_CATERR_LVT3_N
C132  Q_CAP  22UF 6.3V 20% X6S  pkg C0603  page 16 : A = P1V2_AUX ; B = GND

(kicad_pcb
	(version 20260206)
	(generator "pcbnew")
	(generator_version "10.0")
	(general
		(thickness 1.6)
		(legacy_teardrops no)
	)
	(paper "A4")
	(title_block
		(title "12092022_DA0F0TMDCD0_F0T_Management_Board_D_brd_V3_OCP.brd")
		(comment 1 "Grand Teton / footprints 1185-1186 of 1440")
	)
	(layers
		(0 "F.Cu" signal "TOP")
		(4 "In1.Cu" signal "GND")
		(6 "In2.Cu" signal "IN1")
		(8 "In3.Cu" signal "GND1")
		(10 "In4.Cu" signal "IN2")
		(12 "In5.Cu" signal "VCC")
		(14 "In6.Cu" signal "VCC1")
		(16 "In7.Cu" signal "IN3")
		(18 "In8.Cu" signal "GND2")
		(20 "In9.Cu" signal "IN4")
		(22 "In10.Cu" signal "GND3")
		(2 "B.Cu" signal "BOTTOM")
		(9 "F.Adhes" user "F.Adhesive")
		(11 "B.Adhes" user "B.Adhesive")
		(13 "F.Paste" user "Package Geometry/Pastemask Top")
		(15 "B.Paste" user "Package Geometry/Pastemask Bottom")
		(5 "F.SilkS" user "Ref Des/Silkscreen Top")
		(7 "B.SilkS" user "Ref Des/Silkscreen Bottom")
		(1 "F.Mask" user "Board Geometry/Soldermask Top")
		(3 "B.Mask" user "Board Geometry/Soldermask Bottom")
		(17 "Dwgs.User" user "User.Drawings")
		(19 "Cmts.User" user "User.Comments")
		(21 "Eco1.User" user "User.Eco1")
		(23 "Eco2.User" user "User.Eco2")
		(25 "Edge.Cuts" user "Board Geometry/Outline")
		(27 "Margin" user)
		(31 "F.CrtYd" user "Package Geometry/Place Bound Top")
		(29 "B.CrtYd" user "Package Geometry/Place Bound Bottom")
		(35 "F.Fab" user "Ref Des/Assembly Top")
		(33 "B.Fab" user "Ref Des/Assembly Bottom")
	)
	(footprint ""
		(layer "B.Cu")
		(at 83.947 -58.7248 90)
		(property "Reference" "C132"
			(at 0 0 90)
			(layer "B.SilkS")
			(hide yes)
			(effects
				(font
					(size 1.27 1.27)
				)
				(justify mirror)
			)
		)
		(property "Value" ""
			(at 0 0 90)
			(layer "B.Fab")
			(effects
				(font
					(size 1.27 1.27)
				)
				(justify mirror)
			)
		)
		(duplicate_pad_numbers_are_jumpers no)
		(fp_line
			(start 1.2954 -0.5842)
			(end -1.2954 -0.5842)
			(stroke
				(width 0.1524)
				(type default)
			)
			(layer "B.SilkS")
		)
		(fp_line
			(start 0 -0.5842)
			(end 0 0.5842)
			(stroke
				(width 0.1524)
				(type default)
			)
			(layer "B.SilkS")
		)
		(fp_line
			(start -1.2954 -0.5842)
			(end -1.2954 0.5842)
			(stroke
				(width 0.1524)
				(type default)
			)
			(layer "B.SilkS")
		)
		(fp_line
			(start 1.2954 0.5842)
			(end 1.2954 -0.5842)
			(stroke
				(width 0.1524)
				(type default)
			)
			(layer "B.SilkS")
		)
		(fp_line
			(start -1.2954 0.5842)
			(end 1.2954 0.5842)
			(stroke
				(width 0.1524)
				(type default)
			)
			(layer "B.SilkS")
		)
		(fp_line
			(start 0.8636 -0.4572)
			(end -0.8636 -0.4572)
			(stroke
				(width 0.1)
				(type default)
			)
			(layer "B.Fab")
		)
		(fp_line
			(start -0.8636 -0.4572)
			(end -0.8636 -0.4064)
			(stroke
				(width 0.1)
				(type default)
			)
			(layer "B.Fab")
		)
		(fp_line
			(start 1.1938 -0.4064)
			(end 0.8636 -0.4064)
			(stroke
				(width 0.1)
				(type default)
			)
			(layer "B.Fab")
		)
		(fp_line
			(start 0.8636 -0.4064)
			(end 0.8636 -0.4572)
			(stroke
				(width 0.1)
				(type default)
			)
			(layer "B.Fab")
		)
		(fp_line
			(start -0.8636 -0.4064)
			(end -1.1938 -0.4064)
			(stroke
				(width 0.1)
				(type default)
			)
			(layer "B.Fab")
		)
		(fp_line
			(start -1.1938 -0.4064)
			(end -1.1938 0.4064)
			(stroke
				(width 0.1)
				(type default)
			)
			(layer "B.Fab")
		)
		(fp_line
			(start 1.1938 0.4064)
			(end 1.1938 -0.4064)
			(stroke
				(width 0.1)
				(type default)
			)
			(layer "B.Fab")
		)
		(fp_line
			(start 0.8636 0.4064)
			(end 1.1938 0.4064)
			(stroke
				(width 0.1)
				(type default)
			)
			(layer "B.Fab")
		)
		(fp_line
			(start -0.8636 0.4064)
			(end -0.8636 0.4572)
			(stroke
				(width 0.1)
				(type default)
			)
			(layer "B.Fab")
		)
		(fp_line
			(start -1.1938 0.4064)
			(end -0.8636 0.4064)
			(stroke
				(width 0.1)
				(type default)
			)
			(layer "B.Fab")
		)
		(fp_line
			(start 0.8636 0.4572)
			(end 0.8636 0.4064)
			(stroke
				(width 0.1)
				(type default)
			)
			(layer "B.Fab")
		)
		(fp_line
			(start -0.8636 0.4572)
			(end 0.8636 0.4572)
			(stroke
				(width 0.1)
				(type default)
			)
			(layer "B.Fab")
		)
		(pad "1" smd rect
			(at 0.7366 0)
			(size 0.7112 0.8128)
			(layers "B.Cu" "B.Mask" "B.Paste")
			(net "P1V2_AUX")
		)
		(pad "2" smd rect
			(at -0.7366 0)
			(size 0.7112 0.8128)
			(layers "B.Cu" "B.Mask" "B.Paste")
			(net "GND")
		)
	)
	(footprint ""
		(layer "B.Cu")
		(at 16.2814 -83.693 -90)
		(property "Reference" "R163"
			(at 0 0 90)
			(layer "B.SilkS")
			(hide yes)
			(effects
				(font
					(size 1.27 1.27)
				)
				(justify mirror)
			)
		)
		(property "Value" ""
			(at 0 0 90)
			(layer "B.Fab")
			(effects
				(font
					(size 1.27 1.27)
				)
				(justify mirror)
			)
		)
		(duplicate_pad_numbers_are_jumpers no)
		(fp_line
			(start -0.7874 0.4064)
			(end 0.7874 0.4064)
			(stroke
				(width 0.1524)
				(type default)
			)
			(layer "B.SilkS")
		)
		(fp_line
			(start 0.7874 0.4064)
			(end 0.7874 -0.4064)
			(stroke
				(width 0.1524)
				(type default)
			)
			(layer "B.SilkS")
		)
		(fp_line
			(start -0.7874 -0.4064)
			(end -0.7874 0.4064)
			(stroke
				(width 0.1524)
				(type default)
			)
			(layer "B.SilkS")
		)
		(fp_line
			(start 0.7874 -0.4064)
			(end -0.7874 -0.4064)
			(stroke
				(width 0.1524)
				(type default)
			)
			(layer "B.SilkS")
		)
		(fp_line
			(start -0.67945 0.3048)
			(end -0.120396 0.3048)
			(stroke
				(width 0.1)
				(type default)
			)
			(layer "B.Fab")
		)
		(fp_line
			(start -0.120396 0.3048)
			(end -0.120396 0.2794)
			(stroke
				(width 0.1)
				(type default)
			)
			(layer "B.Fab")
		)
		(fp_line
			(start 0.12065 0.3048)
			(end 0.67945 0.3048)
			(stroke
				(width 0.1)
				(type default)
			)
			(layer "B.Fab")
		)
		(fp_line
			(start 0.67945 0.3048)
			(end 0.67945 -0.305054)
			(stroke
				(width 0.1)
				(type default)
			)
			(layer "B.Fab")
		)
		(fp_line
			(start -0.120396 0.2794)
			(end 0.12065 0.2794)
			(stroke
				(width 0.1)
				(type default)
			)
			(layer "B.Fab")
		)
		(fp_line
			(start 0.12065 0.2794)
			(end 0.12065 0.3048)
			(stroke
				(width 0.1)
				(type default)
			)
			(layer "B.Fab")
		)
		(fp_line
			(start -0.12065 -0.2794)
			(end -0.12065 -0.3048)
			(stroke
				(width 0.1)
				(type default)
			)
			(layer "B.Fab")
		)
		(fp_line
			(start 0.12065 -0.2794)
			(end -0.12065 -0.2794)
			(stroke
				(width 0.1)
				(type default)
			)
			(layer "B.Fab")
		)
		(fp_line
			(start -0.67945 -0.3048)
			(end -0.67945 0.3048)
			(stroke
				(width 0.1)
				(type default)
			)
			(layer "B.Fab")
		)
		(fp_line
			(start -0.12065 -0.3048)
			(end -0.67945 -0.3048)
			(stroke
				(width 0.1)
				(type default)
			)
			(layer "B.Fab")
		)
		(fp_line
			(start 0.12065 -0.305054)
			(end 0.12065 -0.2794)
			(stroke
				(width 0.1)
				(type default)
			)
			(layer "B.Fab")
		)
		(fp_line
			(start 0.67945 -0.305054)
			(end 0.12065 -0.305054)
			(stroke
				(width 0.1)
				(type default)
			)
			(layer "B.Fab")
		)
		(pad "1" smd circle
			(at 0.40005 0 90)
			(size 0 0)
			(layers "B.Cu" "B.Mask" "B.Paste")
			(net "P3V3_AUX")
		)
		(pad "2" smd circle
			(at -0.40005 0 90)
			(size 0 0)
			(layers "B.Cu" "B.Mask" "B.Paste")
			(net "FM_CPU_MSMI_CATERR_LVT3_N")
		)
	)
)
